# BASEBOARD_FAB2 (Tioga Pass) — schematic netlist excerpt (pin names and nets, part order shuffled) for the footprints in the layout excerpt that follows; sources: Cadence DE-HDL packaged netlist, KiCad conversion of Wiwynn_Tioga_Pass_MB.brd

R7G14  RES  0.0 5% CHIP  pkg 0402  page 189 : A = JTAG_PLD_TDO_MUX_R ; B = JTAG_PLD_TDO_MUX
C7D4  CAP  1.0UF 16V 10% X6S  pkg 0402  page 92 : A = P3V3 ; B = GND
R12W28  RES  0.0 5% CHIP  pkg 0402  page 218 : A = PU_VR_PVDDQ_DEF_FAULT1 ; B = PWRGD_PVDDQ_DEF

(kicad_pcb
	(version 20260206)
	(generator "pcbnew")
	(generator_version "10.0")
	(general
		(thickness 1.6)
		(legacy_teardrops no)
	)
	(paper "A4")
	(title_block
		(title "Wiwynn_Tioga_Pass_MB.brd")
		(comment 1 "Tioga Pass / footprints 1612-1614 of 4770")
	)
	(layers
		(0 "F.Cu" signal "TOP")
		(4 "In1.Cu" signal "L2GND")
		(6 "In2.Cu" signal "L3")
		(8 "In3.Cu" signal "L4GND")
		(10 "In4.Cu" signal "L5")
		(12 "In5.Cu" signal "L6GND")
		(14 "In6.Cu" signal "L7VCC")
		(16 "In7.Cu" signal "L8VCC")
		(18 "In8.Cu" signal "L9GND")
		(20 "In9.Cu" signal "L10")
		(22 "In10.Cu" signal "L11GND")
		(24 "In11.Cu" signal "L12")
		(26 "In12.Cu" signal "L13GND")
		(2 "B.Cu" signal "BOTTOM")
		(9 "F.Adhes" user "F.Adhesive")
		(11 "B.Adhes" user "B.Adhesive")
		(13 "F.Paste" user "Package Geometry/Pastemask Top")
		(15 "B.Paste" user "Package Geometry/Pastemask Bottom")
		(5 "F.SilkS" user "Ref Des/Silkscreen Top")
		(7 "B.SilkS" user "Ref Des/Silkscreen Bottom")
		(1 "F.Mask" user "Board Geometry/Soldermask Top")
		(3 "B.Mask" user "Board Geometry/Soldermask Bottom")
		(17 "Dwgs.User" user "User.Drawings")
		(19 "Cmts.User" user "User.Comments")
		(21 "Eco1.User" user "User.Eco1")
		(23 "Eco2.User" user "User.Eco2")
		(25 "Edge.Cuts" user "Board Geometry/Outline")
		(27 "Margin" user)
		(31 "F.CrtYd" user "Package Geometry/Place Bound Top")
		(29 "B.CrtYd" user "Package Geometry/Place Bound Bottom")
		(35 "F.Fab" user "Ref Des/Assembly Top")
		(33 "B.Fab" user "Ref Des/Assembly Bottom")
	)
	(footprint ""
		(layer "F.Cu")
		(at 394.6525 -79.375 90)
		(property "Reference" "C7D4"
			(at 0 0 90)
			(layer "F.SilkS")
			(hide yes)
			(effects
				(font
					(size 1.27 1.27)
				)
			)
		)
		(property "Value" ""
			(at 0 0 90)
			(layer "F.Fab")
			(effects
				(font
					(size 1.27 1.27)
				)
			)
		)
		(duplicate_pad_numbers_are_jumpers no)
		(fp_poly
			(pts
				(xy 0.3048 -0.1016) (xy 0.3048 0.9906) (xy -0.3048 0.9906) (xy -0.3048 -0.1016)
			)
			(stroke
				(width 0)
				(type default)
			)
			(fill no)
			(layer "F.CrtYd")
		)
		(fp_line
			(start 0.3048 -0.1016)
			(end -0.3048 -0.1016)
			(stroke
				(width 0.1)
				(type default)
			)
			(layer "F.Fab")
		)
		(fp_line
			(start -0.3048 -0.1016)
			(end -0.3048 0.9906)
			(stroke
				(width 0.1)
				(type default)
			)
			(layer "F.Fab")
		)
		(fp_line
			(start 0.3048 0.9906)
			(end 0.3048 -0.1016)
			(stroke
				(width 0.1)
				(type default)
			)
			(layer "F.Fab")
		)
		(fp_line
			(start -0.3048 0.9906)
			(end 0.3048 0.9906)
			(stroke
				(width 0.1)
				(type default)
			)
			(layer "F.Fab")
		)
		(pad "1" smd rect
			(at 0 0 90)
			(size 0.508 0.508)
			(layers "F.Cu" "F.Mask" "F.Paste")
			(net "P3V3")
		)
		(pad "2" smd rect
			(at 0 0.889 90)
			(size 0.508 0.508)
			(layers "F.Cu" "F.Mask" "F.Paste")
			(net "GND")
		)
		(zone
			(layer "F.Cu")
			(hatch none 0.5)
			(connect_pads
				(clearance 0)
			)
			(min_thickness 0.25)
			(keepout
				(tracks allowed)
				(vias not_allowed)
				(pads allowed)
				(copperpour not_allowed)
				(footprints allowed)
			)
			(placement
				(enabled no)
				(sheetname "")
			)
			(fill
				(thermal_gap 0.5)
				(thermal_bridge_width 0.5)
				(island_removal_mode 0)
			)
			(polygon
				(pts
					(xy 394.9065 -79.121) (xy 394.9065 -79.629) (xy 395.2875 -79.629) (xy 395.2875 -79.121)
				)
			)
		)
		(zone
			(layer "F.Cu")
			(hatch none 0.5)
			(connect_pads
				(clearance 0)
			)
			(min_thickness 0.25)
			(keepout
				(tracks not_allowed)
				(vias allowed)
				(pads allowed)
				(copperpour not_allowed)
				(footprints allowed)
			)
			(placement
				(enabled no)
				(sheetname "")
			)
			(fill
				(thermal_gap 0.5)
				(thermal_bridge_width 0.5)
				(island_removal_mode 0)
			)
			(polygon
				(pts
					(xy 395.2875 -79.121) (xy 395.2875 -79.629) (xy 394.9065 -79.629) (xy 394.9065 -79.121)
				)
			)
		)
	)
	(footprint ""
		(layer "F.Cu")
		(at 363.8804 -135.9916 90)
		(property "Reference" "R12W28"
			(at -0.8382 -0.67818 90)
			(unlocked yes)
			(layer "F.SilkS")
			(effects
				(font
					(size 0.4064 0.254)
					(thickness 0.1524)
				)
				(justify left)
			)
		)
		(property "Value" ""
			(at 0 0 90)
			(layer "F.Fab")
			(effects
				(font
					(size 1.27 1.27)
				)
			)
		)
		(duplicate_pad_numbers_are_jumpers no)
		(fp_poly
			(pts
				(xy -0.2794 -0.1016) (xy 0.2794 -0.1016) (xy 0.2794 0.9906) (xy -0.2794 0.9906)
			)
			(stroke
				(width 0)
				(type default)
			)
			(fill no)
			(layer "F.CrtYd")
		)
		(fp_line
			(start 0.2794 -0.1016)
			(end -0.2794 -0.1016)
			(stroke
				(width 0.1)
				(type default)
			)
			(layer "F.Fab")
		)
		(fp_line
			(start -0.2794 -0.1016)
			(end -0.2794 0.9906)
			(stroke
				(width 0.1)
				(type default)
			)
			(layer "F.Fab")
		)
		(fp_line
			(start 0.2794 0.9906)
			(end 0.2794 -0.1016)
			(stroke
				(width 0.1)
				(type default)
			)
			(layer "F.Fab")
		)
		(fp_line
			(start -0.2794 0.9906)
			(end 0.2794 0.9906)
			(stroke
				(width 0.1)
				(type default)
			)
			(layer "F.Fab")
		)
		(pad "1" smd rect
			(at 0 0 90)
			(size 0.508 0.508)
			(layers "F.Cu" "F.Mask" "F.Paste")
			(net "PU_VR_PVDDQ_DEF_FAULT1")
		)
		(pad "2" smd rect
			(at 0 0.889 90)
			(size 0.508 0.508)
			(layers "F.Cu" "F.Mask" "F.Paste")
			(net "PWRGD_PVDDQ_DEF")
		)
		(zone
			(layer "F.Cu")
			(hatch none 0.5)
			(connect_pads
				(clearance 0)
			)
			(min_thickness 0.25)
			(keepout
				(tracks allowed)
				(vias not_allowed)
				(pads allowed)
				(copperpour not_allowed)
				(footprints allowed)
			)
			(placement
				(enabled no)
				(sheetname "")
			)
			(fill
				(thermal_gap 0.5)
				(thermal_bridge_width 0.5)
				(island_removal_mode 0)
			)
			(polygon
				(pts
					(xy 364.1344 -135.7376) (xy 364.1344 -136.2456) (xy 364.5154 -136.2456) (xy 364.5154 -135.7376)
				)
			)
		)
		(zone
			(layer "F.Cu")
			(hatch none 0.5)
			(connect_pads
				(clearance 0)
			)
			(min_thickness 0.25)
			(keepout
				(tracks not_allowed)
				(vias allowed)
				(pads allowed)
				(copperpour not_allowed)
				(footprints allowed)
			)
			(placement
				(enabled no)
				(sheetname "")
			)
			(fill
				(thermal_gap 0.5)
				(thermal_bridge_width 0.5)
				(island_removal_mode 0)
			)
			(polygon
				(pts
					(xy 364.5154 -135.7376) (xy 364.5154 -136.2456) (xy 364.1344 -136.2456) (xy 364.1344 -135.7376)
				)
			)
		)
	)
	(footprint ""
		(layer "F.Cu")
		(at 399.770092 -0.998474 90)
		(property "Reference" "R7G14"
			(at 0 0 90)
			(layer "F.SilkS")
			(hide yes)
			(effects
				(font
					(size 1.27 1.27)
				)
			)
		)
		(property "Value" ""
			(at 0 0 90)
			(layer "F.Fab")
			(effects
				(font
					(size 1.27 1.27)
				)
			)
		)
		(duplicate_pad_numbers_are_jumpers no)
		(fp_poly
			(pts
				(xy -0.2794 -0.1016) (xy 0.2794 -0.1016) (xy 0.2794 0.9906) (xy -0.2794 0.9906)
			)
			(stroke
				(width 0)
				(type default)
			)
			(fill no)
			(layer "F.CrtYd")
		)
		(fp_line
			(start 0.2794 -0.1016)
			(end -0.2794 -0.1016)
			(stroke
				(width 0.1)
				(type default)
			)
			(layer "F.Fab")
		)
		(fp_line
			(start -0.2794 -0.1016)
			(end -0.2794 0.9906)
			(stroke
				(width 0.1)
				(type default)
			)
			(layer "F.Fab")
		)
		(fp_line
			(start 0.2794 0.9906)
			(end 0.2794 -0.1016)
			(stroke
				(width 0.1)
				(type default)
			)
			(layer "F.Fab")
		)
		(fp_line
			(start -0.2794 0.9906)
			(end 0.2794 0.9906)
			(stroke
				(width 0.1)
				(type default)
			)
			(layer "F.Fab")
		)
		(pad "1" smd rect
			(at 0 0 90)
			(size 0.508 0.508)
			(layers "F.Cu" "F.Mask" "F.Paste")
			(net "JTAG_PLD_TDO_MUX_R")
		)
		(pad "2" smd rect
			(at 0 0.889 90)
			(size 0.508 0.508)
			(layers "F.Cu" "F.Mask" "F.Paste")
			(net "JTAG_PLD_TDO_MUX")
		)
		(zone
			(layer "F.Cu")
			(hatch none 0.5)
			(connect_pads
				(clearance 0)
			)
			(min_thickness 0.25)
			(keepout
				(tracks allowed)
				(vias not_allowed)
				(pads allowed)
				(copperpour not_allowed)
				(footprints allowed)
			)
			(placement
				(enabled no)
				(sheetname "")
			)
			(fill
				(thermal_gap 0.5)
				(thermal_bridge_width 0.5)
				(island_removal_mode 0)
			)
			(polygon
				(pts
					(xy 400.024092 -0.744474) (xy 400.024092 -1.252474) (xy 400.405092 -1.252474) (xy 400.405092 -0.744474)
				)
			)
		)
		(zone
			(layer "F.Cu")
			(hatch none 0.5)
			(connect_pads
				(clearance 0)
			)
			(min_thickness 0.25)
			(keepout
				(tracks not_allowed)
				(vias allowed)
				(pads allowed)
				(copperpour not_allowed)
				(footprints allowed)
			)
			(placement
				(enabled no)
				(sheetname "")
			)
			(fill
				(thermal_gap 0.5)
				(thermal_bridge_width 0.5)
				(island_removal_mode 0)
			)
			(polygon
				(pts
					(xy 400.405092 -0.744474) (xy 400.405092 -1.252474) (xy 400.024092 -1.252474) (xy 400.024092 -0.744474)
				)
			)
		)
	)
)
